# BASEBOARD_FAB2 (Tioga Pass) — schematic netlist excerpt (pin names and nets, part order shuffled) for the footprints in the layout excerpt that follows; sources: Cadence DE-HDL packaged netlist, KiCad conversion of Wiwynn_Tioga_Pass_MB.brd

C25W19  CAP  4.7UF 6.3V 10% X6S  pkg 0603  page 151 : A = P1V2_AUX_BMC ; B = GND
R4D10  RES  27.4 1% CHIP  pkg 0402  page 103 : A = CLK_100M_CPU0_PE_REFCLK_R_DN ; B = CLK_100M_CPU0_PE_REFCLK_DN
C7A10  CAP  1.0UF 16V 10% X6S  pkg 0402  page 236 : A = VR_P1V05_PCH_STBY_PH1_VCIN ; B = GND

(kicad_pcb
	(version 20260206)
	(generator "pcbnew")
	(generator_version "10.0")
	(general
		(thickness 1.6)
		(legacy_teardrops no)
	)
	(paper "A4")
	(title_block
		(title "Wiwynn_Tioga_Pass_MB.brd")
		(comment 1 "Tioga Pass / footprints 498-500 of 4770")
	)
	(layers
		(0 "F.Cu" signal "TOP")
		(4 "In1.Cu" signal "L2GND")
		(6 "In2.Cu" signal "L3")
		(8 "In3.Cu" signal "L4GND")
		(10 "In4.Cu" signal "L5")
		(12 "In5.Cu" signal "L6GND")
		(14 "In6.Cu" signal "L7VCC")
		(16 "In7.Cu" signal "L8VCC")
		(18 "In8.Cu" signal "L9GND")
		(20 "In9.Cu" signal "L10")
		(22 "In10.Cu" signal "L11GND")
		(24 "In11.Cu" signal "L12")
		(26 "In12.Cu" signal "L13GND")
		(2 "B.Cu" signal "BOTTOM")
		(9 "F.Adhes" user "F.Adhesive")
		(11 "B.Adhes" user "B.Adhesive")
		(13 "F.Paste" user "Package Geometry/Pastemask Top")
		(15 "B.Paste" user "Package Geometry/Pastemask Bottom")
		(5 "F.SilkS" user "Ref Des/Silkscreen Top")
		(7 "B.SilkS" user "Ref Des/Silkscreen Bottom")
		(1 "F.Mask" user "Board Geometry/Soldermask Top")
		(3 "B.Mask" user "Board Geometry/Soldermask Bottom")
		(17 "Dwgs.User" user "User.Drawings")
		(19 "Cmts.User" user "User.Comments")
		(21 "Eco1.User" user "User.Eco1")
		(23 "Eco2.User" user "User.Eco2")
		(25 "Edge.Cuts" user "Board Geometry/Outline")
		(27 "Margin" user)
		(31 "F.CrtYd" user "Package Geometry/Place Bound Top")
		(29 "B.CrtYd" user "Package Geometry/Place Bound Bottom")
		(35 "F.Fab" user "Ref Des/Assembly Top")
		(33 "B.Fab" user "Ref Des/Assembly Bottom")
	)
	(footprint ""
		(layer "F.Cu")
		(at 381.576072 -155.432506 180)
		(property "Reference" "C7A10"
			(at 0 0 180)
			(layer "F.SilkS")
			(hide yes)
			(effects
				(font
					(size 1.27 1.27)
				)
			)
		)
		(property "Value" ""
			(at 0 0 180)
			(layer "F.Fab")
			(effects
				(font
					(size 1.27 1.27)
				)
			)
		)
		(duplicate_pad_numbers_are_jumpers no)
		(fp_poly
			(pts
				(xy 0.3048 -0.1016) (xy 0.3048 0.9906) (xy -0.3048 0.9906) (xy -0.3048 -0.1016)
			)
			(stroke
				(width 0)
				(type default)
			)
			(fill no)
			(layer "F.CrtYd")
		)
		(fp_line
			(start 0.3048 0.9906)
			(end 0.3048 -0.1016)
			(stroke
				(width 0.1)
				(type default)
			)
			(layer "F.Fab")
		)
		(fp_line
			(start 0.3048 -0.1016)
			(end -0.3048 -0.1016)
			(stroke
				(width 0.1)
				(type default)
			)
			(layer "F.Fab")
		)
		(fp_line
			(start -0.3048 0.9906)
			(end 0.3048 0.9906)
			(stroke
				(width 0.1)
				(type default)
			)
			(layer "F.Fab")
		)
		(fp_line
			(start -0.3048 -0.1016)
			(end -0.3048 0.9906)
			(stroke
				(width 0.1)
				(type default)
			)
			(layer "F.Fab")
		)
		(pad "1" smd rect
			(at 0 0 180)
			(size 0.508 0.508)
			(layers "F.Cu" "F.Mask" "F.Paste")
			(net "VR_P1V05_PCH_STBY_PH1_VCIN")
		)
		(pad "2" smd rect
			(at 0 0.889 180)
			(size 0.508 0.508)
			(layers "F.Cu" "F.Mask" "F.Paste")
			(net "GND")
		)
		(zone
			(layer "F.Cu")
			(hatch none 0.5)
			(connect_pads
				(clearance 0)
			)
			(min_thickness 0.25)
			(keepout
				(tracks not_allowed)
				(vias allowed)
				(pads allowed)
				(copperpour not_allowed)
				(footprints allowed)
			)
			(placement
				(enabled no)
				(sheetname "")
			)
			(fill
				(thermal_gap 0.5)
				(thermal_bridge_width 0.5)
				(island_removal_mode 0)
			)
			(polygon
				(pts
					(xy 381.830072 -156.067506) (xy 381.322072 -156.067506) (xy 381.322072 -155.686506) (xy 381.830072 -155.686506)
				)
			)
		)
		(zone
			(layer "F.Cu")
			(hatch none 0.5)
			(connect_pads
				(clearance 0)
			)
			(min_thickness 0.25)
			(keepout
				(tracks allowed)
				(vias not_allowed)
				(pads allowed)
				(copperpour not_allowed)
				(footprints allowed)
			)
			(placement
				(enabled no)
				(sheetname "")
			)
			(fill
				(thermal_gap 0.5)
				(thermal_bridge_width 0.5)
				(island_removal_mode 0)
			)
			(polygon
				(pts
					(xy 381.830072 -155.686506) (xy 381.322072 -155.686506) (xy 381.322072 -156.067506) (xy 381.830072 -156.067506)
				)
			)
		)
	)
	(footprint ""
		(layer "F.Cu")
		(at 447.104262 -29.378148 90)
		(property "Reference" "C25W19"
			(at 0.97536 0.76708 0)
			(unlocked yes)
			(layer "F.SilkS")
			(effects
				(font
					(size 0.4064 0.254)
					(thickness 0.1524)
				)
			)
		)
		(property "Value" ""
			(at 0 0 90)
			(layer "F.Fab")
			(effects
				(font
					(size 1.27 1.27)
				)
			)
		)
		(duplicate_pad_numbers_are_jumpers no)
		(fp_poly
			(pts
				(xy -0.4953 -0.2032) (xy 0.4953 -0.2032) (xy 0.4953 1.6002) (xy -0.4953 1.6002)
			)
			(stroke
				(width 0)
				(type default)
			)
			(fill no)
			(layer "F.CrtYd")
		)
		(fp_line
			(start 0.4953 -0.2032)
			(end 0.4953 1.6002)
			(stroke
				(width 0.1)
				(type default)
			)
			(layer "F.Fab")
		)
		(fp_line
			(start -0.4953 -0.2032)
			(end 0.4953 -0.2032)
			(stroke
				(width 0.1)
				(type default)
			)
			(layer "F.Fab")
		)
		(fp_line
			(start 0.4953 1.6002)
			(end -0.4953 1.6002)
			(stroke
				(width 0.1)
				(type default)
			)
			(layer "F.Fab")
		)
		(fp_line
			(start -0.4953 1.6002)
			(end -0.4953 -0.2032)
			(stroke
				(width 0.1)
				(type default)
			)
			(layer "F.Fab")
		)
		(pad "1" smd rect
			(at 0 0 90)
			(size 0.762 0.889)
			(layers "F.Cu" "F.Mask" "F.Paste")
			(net "P1V2_AUX_BMC")
		)
		(pad "2" smd rect
			(at 0 1.397 90)
			(size 0.762 0.889)
			(layers "F.Cu" "F.Mask" "F.Paste")
			(net "GND")
		)
		(zone
			(layer "F.Cu")
			(hatch none 0.5)
			(connect_pads
				(clearance 0)
			)
			(min_thickness 0.25)
			(keepout
				(tracks not_allowed)
				(vias allowed)
				(pads allowed)
				(copperpour not_allowed)
				(footprints allowed)
			)
			(placement
				(enabled no)
				(sheetname "")
			)
			(fill
				(thermal_gap 0.5)
				(thermal_bridge_width 0.5)
				(island_removal_mode 0)
			)
			(polygon
				(pts
					(xy 447.548762 -28.997148) (xy 447.548762 -29.759148) (xy 448.056762 -29.759148) (xy 448.056762 -28.997148)
				)
			)
		)
	)
	(footprint ""
		(layer "F.Cu")
		(at 175.387 -85.217 90)
		(property "Reference" "R4D10"
			(at 0 0 90)
			(layer "F.SilkS")
			(hide yes)
			(effects
				(font
					(size 1.27 1.27)
				)
			)
		)
		(property "Value" ""
			(at 0 0 90)
			(layer "F.Fab")
			(effects
				(font
					(size 1.27 1.27)
				)
			)
		)
		(duplicate_pad_numbers_are_jumpers no)
		(fp_poly
			(pts
				(xy -0.2794 -0.1016) (xy 0.2794 -0.1016) (xy 0.2794 0.9906) (xy -0.2794 0.9906)
			)
			(stroke
				(width 0)
				(type default)
			)
			(fill no)
			(layer "F.CrtYd")
		)
		(fp_line
			(start 0.2794 -0.1016)
			(end -0.2794 -0.1016)
			(stroke
				(width 0.1)
				(type default)
			)
			(layer "F.Fab")
		)
		(fp_line
			(start -0.2794 -0.1016)
			(end -0.2794 0.9906)
			(stroke
				(width 0.1)
				(type default)
			)
			(layer "F.Fab")
		)
		(fp_line
			(start 0.2794 0.9906)
			(end 0.2794 -0.1016)
			(stroke
				(width 0.1)
				(type default)
			)
			(layer "F.Fab")
		)
		(fp_line
			(start -0.2794 0.9906)
			(end 0.2794 0.9906)
			(stroke
				(width 0.1)
				(type default)
			)
			(layer "F.Fab")
		)
		(pad "1" smd rect
			(at 0 0 90)
			(size 0.508 0.508)
			(layers "F.Cu" "F.Mask" "F.Paste")
			(net "CLK_100M_CPU0_PE_REFCLK_R_DN")
		)
		(pad "2" smd rect
			(at 0 0.889 90)
			(size 0.508 0.508)
			(layers "F.Cu" "F.Mask" "F.Paste")
			(net "CLK_100M_CPU0_PE_REFCLK_DN")
		)
		(zone
			(layer "F.Cu")
			(hatch none 0.5)
			(connect_pads
				(clearance 0)
			)
			(min_thickness 0.25)
			(keepout
				(tracks allowed)
				(vias not_allowed)
				(pads allowed)
				(copperpour not_allowed)
				(footprints allowed)
			)
			(placement
				(enabled no)
				(sheetname "")
			)
			(fill
				(thermal_gap 0.5)
				(thermal_bridge_width 0.5)
				(island_removal_mode 0)
			)
			(polygon
				(pts
					(xy 175.641 -84.963) (xy 175.641 -85.471) (xy 176.022 -85.471) (xy 176.022 -84.963)
				)
			)
		)
		(zone
			(layer "F.Cu")
			(hatch none 0.5)
			(connect_pads
				(clearance 0)
			)
			(min_thickness 0.25)
			(keepout
				(tracks not_allowed)
				(vias allowed)
				(pads allowed)
				(copperpour not_allowed)
				(footprints allowed)
			)
			(placement
				(enabled no)
				(sheetname "")
			)
			(fill
				(thermal_gap 0.5)
				(thermal_bridge_width 0.5)
				(island_removal_mode 0)
			)
			(polygon
				(pts
					(xy 176.022 -84.963) (xy 176.022 -85.471) (xy 175.641 -85.471) (xy 175.641 -84.963)
				)
			)
		)
	)
)
